# T6G (Grand Teton) — schematic netlist excerpt (pin names and nets, part order shuffled) for the footprints in the layout excerpt that follows; sources: Cadence DE-HDL packaged netlist, KiCad conversion of 04192023_DAF0TMB3IC0_F0TG_MB_C_brd_V02_OCP.brd

R642  Q_RES  51.1 1% EMPTY  pkg 0201LF  page 353 : A = CLK_100M_RETIMER_CPU1_P3_DP ; B = GND
PR3847  Q_RES  14.3K 1% CHIP  pkg 0402LF  page 141 : A = P12V_OCP_ISET_2 ; B = GND

Q2  MOSFET_DUAL_6P  2N7002KDW IC  pkg SOT363XD  page 166
  S1  = GND
  G1  = BOOT_RDY_BUF_LED
  D2  = BOOT_RDY_LED_N
  S2  = GND
  G2  = BOOT_RDY_LED
  D1  = BOOT_RDY_LED

(kicad_pcb
	(version 20260206)
	(generator "pcbnew")
	(generator_version "10.0")
	(general
		(thickness 1.6)
		(legacy_teardrops no)
	)
	(paper "A4")
	(title_block
		(title "04192023_DAF0TMB3IC0_F0TG_MB_C_brd_V02_OCP.brd")
		(comment 1 "Grand Teton / footprints 4577-4579 of 8354")
	)
	(layers
		(0 "F.Cu" signal "TOP")
		(4 "In1.Cu" signal "GND")
		(6 "In2.Cu" signal "IN1")
		(8 "In3.Cu" signal "GND1")
		(10 "In4.Cu" signal "IN2")
		(12 "In5.Cu" signal "GND2")
		(14 "In6.Cu" signal "IN3")
		(16 "In7.Cu" signal "GND3")
		(18 "In8.Cu" signal "VCC")
		(20 "In9.Cu" signal "VCC1")
		(22 "In10.Cu" signal "GND4")
		(24 "In11.Cu" signal "IN4")
		(26 "In12.Cu" signal "GND5")
		(28 "In13.Cu" signal "IN5")
		(30 "In14.Cu" signal "GND6")
		(32 "In15.Cu" signal "IN6")
		(34 "In16.Cu" signal "GND7")
		(2 "B.Cu" signal "BOTTOM")
		(9 "F.Adhes" user "F.Adhesive")
		(11 "B.Adhes" user "B.Adhesive")
		(13 "F.Paste" user "Package Geometry/Pastemask Top")
		(15 "B.Paste" user "Package Geometry/Pastemask Bottom")
		(5 "F.SilkS" user "Ref Des/Silkscreen Top")
		(7 "B.SilkS" user "Ref Des/Silkscreen Bottom")
		(1 "F.Mask" user "Board Geometry/Soldermask Top")
		(3 "B.Mask" user "Board Geometry/Soldermask Bottom")
		(17 "Dwgs.User" user "User.Drawings")
		(19 "Cmts.User" user "User.Comments")
		(21 "Eco1.User" user "User.Eco1")
		(23 "Eco2.User" user "User.Eco2")
		(25 "Edge.Cuts" user "Board Geometry/Outline")
		(27 "Margin" user)
		(31 "F.CrtYd" user "Package Geometry/Place Bound Top")
		(29 "B.CrtYd" user "Package Geometry/Place Bound Bottom")
		(35 "F.Fab" user "Ref Des/Assembly Top")
		(33 "B.Fab" user "Ref Des/Assembly Bottom")
	)
	(footprint ""
		(layer "F.Cu")
		(at 68.147438 -32.776922 90)
		(property "Reference" "PR3847"
			(at 0 0 90)
			(layer "F.SilkS")
			(hide yes)
			(effects
				(font
					(size 1.27 1.27)
				)
			)
		)
		(property "Value" ""
			(at 0 0 90)
			(layer "F.Fab")
			(effects
				(font
					(size 1.27 1.27)
				)
			)
		)
		(duplicate_pad_numbers_are_jumpers no)
		(fp_line
			(start 0.7874 -0.4064)
			(end 0.7874 0.4064)
			(stroke
				(width 0.1524)
				(type default)
			)
			(layer "F.SilkS")
		)
		(fp_line
			(start -0.7874 -0.4064)
			(end 0.7874 -0.4064)
			(stroke
				(width 0.1524)
				(type default)
			)
			(layer "F.SilkS")
		)
		(fp_line
			(start 0.7874 0.4064)
			(end -0.7874 0.4064)
			(stroke
				(width 0.1524)
				(type default)
			)
			(layer "F.SilkS")
		)
		(fp_line
			(start -0.7874 0.4064)
			(end -0.7874 -0.4064)
			(stroke
				(width 0.1524)
				(type default)
			)
			(layer "F.SilkS")
		)
		(fp_line
			(start -0.12065 -0.305054)
			(end -0.12065 -0.2794)
			(stroke
				(width 0.1)
				(type default)
			)
			(layer "F.Fab")
		)
		(fp_line
			(start -0.67945 -0.305054)
			(end -0.12065 -0.305054)
			(stroke
				(width 0.1)
				(type default)
			)
			(layer "F.Fab")
		)
		(fp_line
			(start 0.67945 -0.3048)
			(end 0.67945 0.3048)
			(stroke
				(width 0.1)
				(type default)
			)
			(layer "F.Fab")
		)
		(fp_line
			(start 0.12065 -0.3048)
			(end 0.67945 -0.3048)
			(stroke
				(width 0.1)
				(type default)
			)
			(layer "F.Fab")
		)
		(fp_line
			(start 0.12065 -0.2794)
			(end 0.12065 -0.3048)
			(stroke
				(width 0.1)
				(type default)
			)
			(layer "F.Fab")
		)
		(fp_line
			(start -0.12065 -0.2794)
			(end 0.12065 -0.2794)
			(stroke
				(width 0.1)
				(type default)
			)
			(layer "F.Fab")
		)
		(fp_line
			(start 0.120396 0.2794)
			(end -0.12065 0.2794)
			(stroke
				(width 0.1)
				(type default)
			)
			(layer "F.Fab")
		)
		(fp_line
			(start -0.12065 0.2794)
			(end -0.12065 0.3048)
			(stroke
				(width 0.1)
				(type default)
			)
			(layer "F.Fab")
		)
		(fp_line
			(start 0.67945 0.3048)
			(end 0.120396 0.3048)
			(stroke
				(width 0.1)
				(type default)
			)
			(layer "F.Fab")
		)
		(fp_line
			(start 0.120396 0.3048)
			(end 0.120396 0.2794)
			(stroke
				(width 0.1)
				(type default)
			)
			(layer "F.Fab")
		)
		(fp_line
			(start -0.12065 0.3048)
			(end -0.67945 0.3048)
			(stroke
				(width 0.1)
				(type default)
			)
			(layer "F.Fab")
		)
		(fp_line
			(start -0.67945 0.3048)
			(end -0.67945 -0.305054)
			(stroke
				(width 0.1)
				(type default)
			)
			(layer "F.Fab")
		)
		(pad "1" smd circle
			(at -0.40005 0 90)
			(size 0 0)
			(layers "F.Cu" "F.Mask" "F.Paste")
			(net "P12V_OCP_ISET_2")
		)
		(pad "2" smd circle
			(at 0.40005 0 90)
			(size 0 0)
			(layers "F.Cu" "F.Mask" "F.Paste")
			(net "GND")
		)
	)
	(footprint ""
		(layer "F.Cu")
		(at 340.969346 -20.093686 -90)
		(property "Reference" "Q2"
			(at -0.023114 1.751076 90)
			(unlocked yes)
			(layer "F.SilkS")
			(effects
				(font
					(size 0.7874 0.5842)
					(thickness 0.1524)
				)
				(justify left)
			)
		)
		(property "Value" ""
			(at 0 0 270)
			(layer "F.Fab")
			(effects
				(font
					(size 1.27 1.27)
				)
			)
		)
		(duplicate_pad_numbers_are_jumpers no)
		(fp_line
			(start -1.332738 1.100074)
			(end -1.332738 -1.100074)
			(stroke
				(width 0.1524)
				(type default)
			)
			(layer "F.SilkS")
		)
		(fp_line
			(start 1.332738 1.100074)
			(end -1.332738 1.100074)
			(stroke
				(width 0.1524)
				(type default)
			)
			(layer "F.SilkS")
		)
		(fp_line
			(start 0 -0.541274)
			(end 0.4826 -1.100074)
			(stroke
				(width 0.1524)
				(type default)
			)
			(layer "F.SilkS")
		)
		(fp_line
			(start -1.332738 -1.100074)
			(end -0.4826 -1.100074)
			(stroke
				(width 0.1524)
				(type default)
			)
			(layer "F.SilkS")
		)
		(fp_line
			(start -0.4826 -1.100074)
			(end 0 -0.541274)
			(stroke
				(width 0.1524)
				(type default)
			)
			(layer "F.SilkS")
		)
		(fp_line
			(start 0.4826 -1.100074)
			(end 1.332738 -1.100074)
			(stroke
				(width 0.1524)
				(type default)
			)
			(layer "F.SilkS")
		)
		(fp_line
			(start 1.332738 -1.100074)
			(end 1.332738 1.100074)
			(stroke
				(width 0.1524)
				(type default)
			)
			(layer "F.SilkS")
		)
		(fp_poly
			(pts
				(xy -2.067306 -0.649986) (xy -2.769362 -0.298958) (xy -2.769362 -1.001014)
			)
			(stroke
				(width 0)
				(type default)
			)
			(fill yes)
			(layer "F.SilkS")
		)
		(fp_line
			(start -0.674878 1.100074)
			(end -0.674878 -1.100074)
			(stroke
				(width 0.1)
				(type default)
			)
			(layer "F.Fab")
		)
		(fp_line
			(start 0.674878 1.100074)
			(end -0.674878 1.100074)
			(stroke
				(width 0.1)
				(type default)
			)
			(layer "F.Fab")
		)
		(fp_line
			(start -0.674878 -1.100074)
			(end 0.674878 -1.100074)
			(stroke
				(width 0.1)
				(type default)
			)
			(layer "F.Fab")
		)
		(fp_line
			(start 0.674878 -1.100074)
			(end 0.674878 1.100074)
			(stroke
				(width 0.1)
				(type default)
			)
			(layer "F.Fab")
		)
		(fp_poly
			(pts
				(xy -2.2352 -0.298958) (xy -2.2352 -1.001014) (xy -1.533144 -0.649986)
			)
			(stroke
				(width 0)
				(type default)
			)
			(fill yes)
			(layer "F.Fab")
		)
		(pad "1" smd rect
			(at -0.94996 -0.649986)
			(size 0.4318 0.508)
			(layers "F.Cu" "F.Mask" "F.Paste")
			(net "GND")
		)
		(pad "2" smd rect
			(at -0.94996 0)
			(size 0.4318 0.508)
			(layers "F.Cu" "F.Mask" "F.Paste")
			(net "BOOT_RDY_BUF_LED")
		)
		(pad "3" smd rect
			(at -0.94996 0.649986)
			(size 0.4318 0.508)
			(layers "F.Cu" "F.Mask" "F.Paste")
			(net "BOOT_RDY_LED_N")
		)
		(pad "4" smd rect
			(at 0.94996 0.649986)
			(size 0.4318 0.508)
			(layers "F.Cu" "F.Mask" "F.Paste")
			(net "GND")
		)
		(pad "5" smd rect
			(at 0.94996 0)
			(size 0.4318 0.508)
			(layers "F.Cu" "F.Mask" "F.Paste")
			(net "BOOT_RDY_LED")
		)
		(pad "6" smd rect
			(at 0.94996 -0.649986)
			(size 0.4318 0.508)
			(layers "F.Cu" "F.Mask" "F.Paste")
			(net "BOOT_RDY_LED")
		)
	)
	(footprint ""
		(layer "F.Cu")
		(at 110.643924 -388.030974 90)
		(property "Reference" "R642"
			(at 0 0 90)
			(layer "F.SilkS")
			(hide yes)
			(effects
				(font
					(size 1.27 1.27)
				)
			)
		)
		(property "Value" ""
			(at 0 0 90)
			(layer "F.Fab")
			(effects
				(font
					(size 1.27 1.27)
				)
			)
		)
		(duplicate_pad_numbers_are_jumpers no)
		(fp_line
			(start 0.32512 -0.175006)
			(end 0.32512 0.175006)
			(stroke
				(width 0.1)
				(type default)
			)
			(layer "F.Fab")
		)
		(fp_line
			(start -0.32512 -0.175006)
			(end 0.32512 -0.175006)
			(stroke
				(width 0.1)
				(type default)
			)
			(layer "F.Fab")
		)
		(fp_line
			(start 0.32512 0.175006)
			(end -0.32512 0.175006)
			(stroke
				(width 0.1)
				(type default)
			)
			(layer "F.Fab")
		)
		(fp_line
			(start -0.32512 0.175006)
			(end -0.32512 -0.175006)
			(stroke
				(width 0.1)
				(type default)
			)
			(layer "F.Fab")
		)
		(pad "1" smd rect
			(at -0.2667 0 90)
			(size 0.3048 0.381)
			(layers "F.Cu" "F.Mask" "F.Paste")
			(net "CLK_100M_RETIMER_CPU1_P3_DP")
		)
		(pad "2" smd rect
			(at 0.2667 0 270)
			(size 0.3048 0.381)
			(layers "F.Cu" "F.Mask" "F.Paste")
			(net "GND")
		)
	)
)
